(kicad_pcb
	(version 20241229)
	(generator "pcbnew")
	(generator_version "9.0")
	(general
		(thickness 1.61)
		(legacy_teardrops no)
	)
	(paper "A3")
	(title_block
		(title "RDIMM DDR5 Tester")
		(date "2026-05-21")
		(rev "2.2.0")
		(company "Antmicro")
		(comment 9 "footprints 209-213 of 796")
	)
	(layers
		(0 "F.Cu" signal)
		(4 "In1.Cu" power)
		(6 "In2.Cu" mixed)
		(8 "In3.Cu" power)
		(10 "In4.Cu" mixed)
		(12 "In5.Cu" power)
		(14 "In6.Cu" mixed)
		(16 "In7.Cu" power)
		(18 "In8.Cu" power)
		(20 "In9.Cu" mixed)
		(22 "In10.Cu" power)
		(2 "B.Cu" signal)
		(9 "F.Adhes" user "F.Adhesive")
		(11 "B.Adhes" user "B.Adhesive")
		(13 "F.Paste" user)
		(15 "B.Paste" user)
		(5 "F.SilkS" user "F.Silkscreen")
		(7 "B.SilkS" user "B.Silkscreen")
		(1 "F.Mask" user)
		(3 "B.Mask" user)
		(17 "Dwgs.User" user "User.Drawings")
		(19 "Cmts.User" user "User.Comments")
		(21 "Eco1.User" user "User.Eco1")
		(23 "Eco2.User" user "User.Eco2")
		(25 "Edge.Cuts" user)
		(27 "Margin" user)
		(31 "F.CrtYd" user "F.Courtyard")
		(29 "B.CrtYd" user "B.Courtyard")
		(35 "F.Fab" user)
		(33 "B.Fab" user)
	)
	(footprint "antmicro-footprints:LED_0603_1608Metric_G"
		(layer "F.Cu")
		(at 139.424499 185.549 90)
		(descr "LED SMD 0603 Green")
		(tags "LED SMD 0603 Green")
		(property "Reference" "D12"
			(at -0.001 -0.901 90)
			(layer "F.SilkS")
			(hide yes)
			(effects
				(font
					(size 0.7 0.7)
					(thickness 0.15)
				)
				(justify left bottom)
			)
		)
		(property "Value" "LED_G_0603_KP-1608CGCK"
			(at -0.001 1.599 90)
			(layer "F.Fab")
			(effects
				(font
					(size 0.7 0.7)
					(thickness 0.15)
				)
				(justify left bottom)
			)
		)
		(property "Datasheet" "http://www.kingbright.com/attachments/file/psearch//000/00/00/KP-1608CGCK(Ver.23B).pdf"
			(at 0 0 90)
			(layer "F.Fab")
			(hide yes)
			(effects
				(font
					(size 1.27 1.27)
					(thickness 0.15)
				)
			)
		)
		(property "MPN" "KP-1608CGCK"
			(at 0 0 90)
			(unlocked yes)
			(layer "F.Fab")
			(hide yes)
			(effects
				(font
					(size 1 1)
					(thickness 0.15)
				)
			)
		)
		(property "Manufacturer" "Kingbright"
			(at 0 0 90)
			(unlocked yes)
			(layer "F.Fab")
			(hide yes)
			(effects
				(font
					(size 1 1)
					(thickness 0.15)
				)
			)
		)
		(property "Color" "Green"
			(at 0 0 90)
			(unlocked yes)
			(layer "F.Fab")
			(hide yes)
			(effects
				(font
					(size 1 1)
					(thickness 0.15)
				)
			)
		)
		(property "Author" "Antmicro"
			(at 0 0 90)
			(unlocked yes)
			(layer "F.Fab")
			(hide yes)
			(effects
				(font
					(size 1 1)
					(thickness 0.15)
				)
			)
		)
		(property "License" "Apache-2.0"
			(at 0 0 90)
			(unlocked yes)
			(layer "F.Fab")
			(hide yes)
			(effects
				(font
					(size 1 1)
					(thickness 0.15)
				)
			)
		)
		(sheetname "/Debug FTDI + VNA/")
		(sheetfile "debug-ftdi.kicad_sch")
		(attr smd)
		(fp_line
			(start 0.22 -0.35)
			(end -0.22 -0.35)
			(stroke
				(width 0.15)
				(type solid)
			)
			(layer "F.SilkS")
		)
		(fp_line
			(start -1.18 -0.319)
			(end -1.18 0.321)
			(stroke
				(width 0.15)
				(type solid)
			)
			(layer "F.SilkS")
		)
		(fp_line
			(start 0.105328 0.001008)
			(end 0.24 0.001)
			(stroke
				(width 0.1)
				(type solid)
			)
			(layer "F.SilkS")
		)
		(fp_line
			(start -0.094672 0.001008)
			(end 0.105328 -0.198992)
			(stroke
				(width 0.1)
				(type solid)
			)
			(layer "F.SilkS")
		)
		(fp_line
			(start -0.094672 0.001008)
			(end -0.24 0.001008)
			(stroke
				(width 0.1)
				(type solid)
			)
			(layer "F.SilkS")
		)
		(fp_line
			(start 0.105328 0.201008)
			(end 0.105328 -0.198992)
			(stroke
				(width 0.1)
				(type solid)
			)
			(layer "F.SilkS")
		)
		(fp_line
			(start 0.105328 0.201008)
			(end -0.094672 0.001008)
			(stroke
				(width 0.1)
				(type solid)
			)
			(layer "F.SilkS")
		)
		(fp_line
			(start -0.094672 0.201008)
			(end -0.094672 -0.198992)
			(stroke
				(width 0.1)
				(type solid)
			)
			(layer "F.SilkS")
		)
		(fp_line
			(start 0.22 0.35)
			(end -0.22 0.35)
			(stroke
				(width 0.15)
				(type solid)
			)
			(layer "F.SilkS")
		)
		(fp_rect
			(start 1.25 0.65)
			(end -1.25 -0.65)
			(stroke
				(width 0.05)
				(type solid)
			)
			(fill no)
			(layer "F.CrtYd")
		)
		(fp_line
			(start 0.201 -0.202)
			(end -0.101 0)
			(stroke
				(width 0.15)
				(type solid)
			)
			(layer "F.Fab")
		)
		(fp_line
			(start -0.199 -0.202)
			(end -0.199 0.1)
			(stroke
				(width 0.15)
				(type solid)
			)
			(layer "F.Fab")
		)
		(fp_line
			(start 0.599 0)
			(end 0.201 0)
			(stroke
				(width 0.15)
				(type solid)
			)
			(layer "F.Fab")
		)
		(fp_line
			(start 0.201 0)
			(end 0.201 -0.202)
			(stroke
				(width 0.15)
				(type solid)
			)
			(layer "F.Fab")
		)
		(fp_line
			(start -0.101 0)
			(end 0.201 0.2)
			(stroke
				(width 0.15)
				(type solid)
			)
			(layer "F.Fab")
		)
		(fp_line
			(start -0.199 0)
			(end -0.597 0)
			(stroke
				(width 0.15)
				(type solid)
			)
			(layer "F.Fab")
		)
		(fp_line
			(start 0.201 0.2)
			(end 0.201 0)
			(stroke
				(width 0.15)
				(type solid)
			)
			(layer "F.Fab")
		)
		(fp_line
			(start -0.199 0.2)
			(end -0.199 0.1)
			(stroke
				(width 0.15)
				(type solid)
			)
			(layer "F.Fab")
		)
		(fp_rect
			(start 0.848 0.4)
			(end -0.85 -0.402)
			(stroke
				(width 0.15)
				(type solid)
			)
			(fill no)
			(layer "F.Fab")
		)
		(fp_text user "License: Apache-2.0"
			(at -1.4224 3.599 90)
			(layer "F.Fab")
			(effects
				(font
					(size 0.7 0.7)
					(thickness 0.15)
				)
				(justify left bottom)
			)
		)
		(fp_text user "${REFERENCE}"
			(at -1.4224 5.999 90)
			(layer "F.Fab")
			(effects
				(font
					(size 0.7 0.7)
					(thickness 0.15)
				)
				(justify left bottom)
			)
		)
		(fp_text user "Author: Antmicro"
			(at -1.4224 4.799 90)
			(layer "F.Fab")
			(effects
				(font
					(size 0.7 0.7)
					(thickness 0.15)
				)
				(justify left bottom)
			)
		)
		(pad "1" smd roundrect
			(at -0.7 0 270)
			(size 0.8 1)
			(layers "F.Cu" "F.Mask" "F.Paste")
			(roundrect_rratio 0.2)
			(net 1 "GND")
			(pinfunction "C")
			(pintype "passive")
		)
		(pad "2" smd roundrect
			(at 0.7 0 270)
			(size 0.8 1)
			(layers "F.Cu" "F.Mask" "F.Paste")
			(roundrect_rratio 0.2)
			(net 42 "Net-(D12-A)")
			(pinfunction "A")
			(pintype "passive")
		)
	)
	(footprint "antmicro-footprints:TP_SMD_0.75mm"
		(layer "F.Cu")
		(at 233.875 132.075)
		(property "Reference" "TP27"
			(at -2.25 1.525 0)
			(layer "F.SilkS")
			(effects
				(font
					(size 0.7 0.7)
					(thickness 0.15)
				)
				(justify left bottom)
			)
		)
		(property "Value" "TP_0.75mm_SMD"
			(at 0 1.2 0)
			(layer "F.Fab")
			(effects
				(font
					(size 0.7 0.7)
					(thickness 0.15)
				)
				(justify left bottom)
			)
		)
		(property "MPN" ""
			(at 0 0 0)
			(unlocked yes)
			(layer "F.Fab")
			(hide yes)
			(effects
				(font
					(size 1 1)
					(thickness 0.15)
				)
			)
		)
		(property "Manufacturer" ""
			(at 0 0 0)
			(unlocked yes)
			(layer "F.Fab")
			(hide yes)
			(effects
				(font
					(size 1 1)
					(thickness 0.15)
				)
			)
		)
		(property "Author" "Antmicro"
			(at 0 0 0)
			(unlocked yes)
			(layer "F.Fab")
			(hide yes)
			(effects
				(font
					(size 1 1)
					(thickness 0.15)
				)
			)
		)
		(property "License" "Apache-2.0"
			(at 0 0 0)
			(unlocked yes)
			(layer "F.Fab")
			(hide yes)
			(effects
				(font
					(size 1 1)
					(thickness 0.15)
				)
			)
		)
		(sheetname "/I^{2}C + I3C/")
		(sheetfile "i2c.kicad_sch")
		(attr exclude_from_pos_files exclude_from_bom)
		(fp_circle
			(center 0 0)
			(end 0.475 0)
			(stroke
				(width 0.05)
				(type default)
			)
			(fill no)
			(layer "F.CrtYd")
		)
		(fp_text user "License: Apache-2.0"
			(at -0.4 5.101 0)
			(layer "F.Fab")
			(effects
				(font
					(size 0.7 0.7)
					(thickness 0.15)
				)
				(justify left bottom)
			)
		)
		(fp_text user "Author: Antmicro"
			(at -0.4 3.901 0)
			(layer "F.Fab")
			(effects
				(font
					(size 0.7 0.7)
					(thickness 0.15)
				)
				(justify left bottom)
			)
		)
		(fp_text user "${REFERENCE}"
			(at -0.4 2.7 0)
			(layer "F.Fab")
			(effects
				(font
					(size 0.7 0.7)
					(thickness 0.15)
				)
				(justify left bottom)
			)
		)
		(pad "1" smd circle
			(at 0 0)
			(size 0.75 0.75)
			(layers "F.Cu" "F.Mask")
			(net 473 "Net-(R126-Pad1)")
			(pinfunction "1")
			(pintype "passive")
		)
	)
	(footprint "antmicro-footprints:C_0402_1005Metric"
		(layer "F.Cu")
		(at 118.19 146.61)
		(descr "Capacitor SMD 0402")
		(tags "capacitor SMD 0402")
		(property "Reference" "C301"
			(at -3.74 0.39 0)
			(layer "F.SilkS")
			(effects
				(font
					(size 0.7 0.7)
					(thickness 0.15)
				)
				(justify left bottom)
			)
		)
		(property "Value" "C_10u_6.3V_0402"
			(at -1.022927 2.155213 0)
			(layer "F.Fab")
			(effects
				(font
					(size 0.7 0.7)
					(thickness 0.15)
				)
				(justify left bottom)
			)
		)
		(property "Datasheet" "https://www.murata.com/products/productdetail?partno=GRM155R60J106ME15%23"
			(at 0 0 0)
			(layer "F.Fab")
			(hide yes)
			(effects
				(font
					(size 1.27 1.27)
					(thickness 0.15)
				)
			)
		)
		(property "MPN" "GRM155R60J106ME15D"
			(at 0 0 0)
			(unlocked yes)
			(layer "F.Fab")
			(hide yes)
			(effects
				(font
					(size 1 1)
					(thickness 0.15)
				)
			)
		)
		(property "Manufacturer" "Murata"
			(at 0 0 0)
			(unlocked yes)
			(layer "F.Fab")
			(hide yes)
			(effects
				(font
					(size 1 1)
					(thickness 0.15)
				)
			)
		)
		(property "License" "Apache-2.0"
			(at 0 0 0)
			(unlocked yes)
			(layer "F.Fab")
			(hide yes)
			(effects
				(font
					(size 1 1)
					(thickness 0.15)
				)
			)
		)
		(property "Author" "Antmicro"
			(at 0 0 0)
			(unlocked yes)
			(layer "F.Fab")
			(hide yes)
			(effects
				(font
					(size 1 1)
					(thickness 0.15)
				)
			)
		)
		(property "Val" "10u"
			(at 0 0 0)
			(unlocked yes)
			(layer "F.Fab")
			(hide yes)
			(effects
				(font
					(size 1 1)
					(thickness 0.15)
				)
			)
		)
		(property "Voltage" "6.3V"
			(at 0 0 0)
			(unlocked yes)
			(layer "F.Fab")
			(hide yes)
			(effects
				(font
					(size 1 1)
					(thickness 0.15)
				)
			)
		)
		(property "Dielectric" "X5R"
			(at 0 0 0)
			(unlocked yes)
			(layer "F.Fab")
			(hide yes)
			(effects
				(font
					(size 1 1)
					(thickness 0.15)
				)
			)
		)
		(sheetname "/HDMI + SD Card/")
		(sheetfile "hdmi-sd-card.kicad_sch")
		(attr smd)
		(fp_rect
			(start -0.925 -0.47)
			(end 0.925 0.47)
			(stroke
				(width 0.05)
				(type default)
			)
			(fill no)
			(layer "F.CrtYd")
		)
		(fp_line
			(start -0.494 -0.25)
			(end 0.504 -0.25)
			(stroke
				(width 0.15)
				(type solid)
			)
			(layer "F.Fab")
		)
		(fp_line
			(start -0.494 0.248)
			(end -0.494 -0.25)
			(stroke
				(width 0.15)
				(type solid)
			)
			(layer "F.Fab")
		)
		(fp_line
			(start 0.504 -0.25)
			(end 0.504 0.248)
			(stroke
				(width 0.15)
				(type solid)
			)
			(layer "F.Fab")
		)
		(fp_line
			(start 0.504 0.248)
			(end -0.494 0.248)
			(stroke
				(width 0.15)
				(type solid)
			)
			(layer "F.Fab")
		)
		(fp_text user "Author: Antmicro"
			(at -0.939 3.399 0)
			(layer "F.Fab")
			(effects
				(font
					(size 0.7 0.7)
					(thickness 0.15)
				)
				(justify left bottom)
			)
		)
		(fp_text user "${REFERENCE}"
			(at -0.939 4.599 0)
			(layer "F.Fab")
			(effects
				(font
					(size 0.7 0.7)
					(thickness 0.15)
				)
				(justify left bottom)
			)
		)
		(fp_text user "License: Apache-2.0"
			(at -0.939 5.799 0)
			(layer "F.Fab")
			(effects
				(font
					(size 0.7 0.7)
					(thickness 0.15)
				)
				(justify left bottom)
			)
		)
		(pad "1" smd roundrect
			(at -0.48 0)
			(size 0.59 0.64)
			(layers "F.Cu" "F.Mask" "F.Paste")
			(roundrect_rratio 0.25)
			(net 1 "GND")
			(pintype "passive")
		)
		(pad "2" smd roundrect
			(at 0.48 0)
			(size 0.59 0.64)
			(layers "F.Cu" "F.Mask" "F.Paste")
			(roundrect_rratio 0.25)
			(net 322 "Net-(C300-Pad2)")
			(pintype "passive")
		)
	)
	(footprint "antmicro-footprints:TP_SMD_0.75mm"
		(layer "F.Cu")
		(at 155.43 161.799999)
		(property "Reference" "TP6"
			(at -2.6 0.45 0)
			(layer "F.SilkS")
			(effects
				(font
					(size 0.7 0.7)
					(thickness 0.15)
				)
				(justify left bottom)
			)
		)
		(property "Value" "TP_0.75mm_SMD"
			(at 0 1.2 0)
			(layer "F.Fab")
			(effects
				(font
					(size 0.7 0.7)
					(thickness 0.15)
				)
				(justify left bottom)
			)
		)
		(property "MPN" ""
			(at 0 0 0)
			(unlocked yes)
			(layer "F.Fab")
			(hide yes)
			(effects
				(font
					(size 1 1)
					(thickness 0.15)
				)
			)
		)
		(property "Manufacturer" ""
			(at 0 0 0)
			(unlocked yes)
			(layer "F.Fab")
			(hide yes)
			(effects
				(font
					(size 1 1)
					(thickness 0.15)
				)
			)
		)
		(property "Author" "Antmicro"
			(at 0 0 0)
			(unlocked yes)
			(layer "F.Fab")
			(hide yes)
			(effects
				(font
					(size 1 1)
					(thickness 0.15)
				)
			)
		)
		(property "License" "Apache-2.0"
			(at 0 0 0)
			(unlocked yes)
			(layer "F.Fab")
			(hide yes)
			(effects
				(font
					(size 1 1)
					(thickness 0.15)
				)
			)
		)
		(sheetname "/FPGA MGT Interface/")
		(sheetfile "fpga-mgt.kicad_sch")
		(attr exclude_from_pos_files exclude_from_bom)
		(fp_circle
			(center 0 0)
			(end 0.475 0)
			(stroke
				(width 0.05)
				(type default)
			)
			(fill no)
			(layer "F.CrtYd")
		)
		(fp_text user "Author: Antmicro"
			(at -0.4 3.901 0)
			(layer "F.Fab")
			(effects
				(font
					(size 0.7 0.7)
					(thickness 0.15)
				)
				(justify left bottom)
			)
		)
		(fp_text user "${REFERENCE}"
			(at -0.4 2.7 0)
			(layer "F.Fab")
			(effects
				(font
					(size 0.7 0.7)
					(thickness 0.15)
				)
				(justify left bottom)
			)
		)
		(fp_text user "License: Apache-2.0"
			(at -0.4 5.101 0)
			(layer "F.Fab")
			(effects
				(font
					(size 0.7 0.7)
					(thickness 0.15)
				)
				(justify left bottom)
			)
		)
		(pad "1" smd circle
			(at 0 0)
			(size 0.75 0.75)
			(layers "F.Cu" "F.Mask")
			(net 542 "Net-(U39-RATE1)")
			(pinfunction "1")
			(pintype "passive")
		)
	)
	(footprint "antmicro-footprints:C_0402_1005Metric"
		(layer "F.Cu")
		(at 241.774499 164.4 90)
		(descr "Capacitor SMD 0402")
		(tags "capacitor SMD 0402")
		(property "Reference" "C207"
			(at 0.875 0.425501 90)
			(layer "F.SilkS")
			(effects
				(font
					(size 0.7 0.7)
					(thickness 0.15)
				)
				(justify left bottom)
			)
		)
		(property "Value" "C_100n_0402"
			(at -1.022927 2.155213 90)
			(layer "F.Fab")
			(effects
				(font
					(size 0.7 0.7)
					(thickness 0.15)
				)
				(justify left bottom)
			)
		)
		(property "Datasheet" "https://www.murata.com/products/productdetail?partno=GRM155R61H104KE14%23"
			(at 0 0 90)
			(layer "F.Fab")
			(hide yes)
			(effects
				(font
					(size 1.27 1.27)
					(thickness 0.15)
				)
			)
		)
		(property "Manufacturer" "Murata"
			(at 0 0 90)
			(unlocked yes)
			(layer "F.Fab")
			(hide yes)
			(effects
				(font
					(size 1 1)
					(thickness 0.15)
				)
			)
		)
		(property "MPN" "GRM155R61H104KE14D"
			(at 0 0 90)
			(unlocked yes)
			(layer "F.Fab")
			(hide yes)
			(effects
				(font
					(size 1 1)
					(thickness 0.15)
				)
			)
		)
		(property "Val" "100n"
			(at 0 0 90)
			(unlocked yes)
			(layer "F.Fab")
			(hide yes)
			(effects
				(font
					(size 1 1)
					(thickness 0.15)
				)
			)
		)
		(property "License" "Apache-2.0"
			(at 0 0 90)
			(unlocked yes)
			(layer "F.Fab")
			(hide yes)
			(effects
				(font
					(size 1 1)
					(thickness 0.15)
				)
			)
		)
		(property "Author" "Antmicro"
			(at 0 0 90)
			(unlocked yes)
			(layer "F.Fab")
			(hide yes)
			(effects
				(font
					(size 1 1)
					(thickness 0.15)
				)
			)
		)
		(property "Voltage" "50V"
			(at 0 0 90)
			(unlocked yes)
			(layer "F.Fab")
			(hide yes)
			(effects
				(font
					(size 1 1)
					(thickness 0.15)
				)
			)
		)
		(property "Dielectric" "X5R"
			(at 0 0 90)
			(unlocked yes)
			(layer "F.Fab")
			(hide yes)
			(effects
				(font
					(size 1 1)
					(thickness 0.15)
				)
			)
		)
		(sheetname "/Supply/")
		(sheetfile "supply.kicad_sch")
		(attr smd)
		(fp_rect
			(start -0.925 -0.47)
			(end 0.925 0.47)
			(stroke
				(width 0.05)
				(type default)
			)
			(fill no)
			(layer "F.CrtYd")
		)
		(fp_line
			(start 0.504 -0.25)
			(end 0.504 0.248)
			(stroke
				(width 0.15)
				(type solid)
			)
			(layer "F.Fab")
		)
		(fp_line
			(start -0.494 -0.25)
			(end 0.504 -0.25)
			(stroke
				(width 0.15)
				(type solid)
			)
			(layer "F.Fab")
		)
		(fp_line
			(start 0.504 0.248)
			(end -0.494 0.248)
			(stroke
				(width 0.15)
				(type solid)
			)
			(layer "F.Fab")
		)
		(fp_line
			(start -0.494 0.248)
			(end -0.494 -0.25)
			(stroke
				(width 0.15)
				(type solid)
			)
			(layer "F.Fab")
		)
		(fp_text user "License: Apache-2.0"
			(at -0.939 5.799 90)
			(layer "F.Fab")
			(effects
				(font
					(size 0.7 0.7)
					(thickness 0.15)
				)
				(justify left bottom)
			)
		)
		(fp_text user "${REFERENCE}"
			(at -0.939 4.599 90)
			(layer "F.Fab")
			(effects
				(font
					(size 0.7 0.7)
					(thickness 0.15)
				)
				(justify left bottom)
			)
		)
		(fp_text user "Author: Antmicro"
			(at -0.939 3.399 90)
			(layer "F.Fab")
			(effects
				(font
					(size 0.7 0.7)
					(thickness 0.15)
				)
				(justify left bottom)
			)
		)
		(pad "1" smd roundrect
			(at -0.48 0 90)
			(size 0.59 0.64)
			(layers "F.Cu" "F.Mask" "F.Paste")
			(roundrect_rratio 0.25)
			(net 38 "+3V3_AON")
			(pintype "passive")
		)
		(pad "2" smd roundrect
			(at 0.48 0 90)
			(size 0.59 0.64)
			(layers "F.Cu" "F.Mask" "F.Paste")
			(roundrect_rratio 0.25)
			(net 1 "GND")
			(pintype "passive")
		)
	)
)
